(kicad_pcb
	(version 20260206)
	(generator "pcbnew")
	(generator_version "10.0")
	(general
		(thickness 1.6)
		(legacy_teardrops no)
	)
	(paper "A4")
	(title_block
		(title "04192023_DAF0TMB3IC0_F0TG_MB_C_brd_V02_OCP.brd")
		(comment 1 "Grand Teton / footprints 322-328 of 8354")
	)
	(layers
		(0 "F.Cu" signal "TOP")
		(4 "In1.Cu" signal "GND")
		(6 "In2.Cu" signal "IN1")
		(8 "In3.Cu" signal "GND1")
		(10 "In4.Cu" signal "IN2")
		(12 "In5.Cu" signal "GND2")
		(14 "In6.Cu" signal "IN3")
		(16 "In7.Cu" signal "GND3")
		(18 "In8.Cu" signal "VCC")
		(20 "In9.Cu" signal "VCC1")
		(22 "In10.Cu" signal "GND4")
		(24 "In11.Cu" signal "IN4")
		(26 "In12.Cu" signal "GND5")
		(28 "In13.Cu" signal "IN5")
		(30 "In14.Cu" signal "GND6")
		(32 "In15.Cu" signal "IN6")
		(34 "In16.Cu" signal "GND7")
		(2 "B.Cu" signal "BOTTOM")
		(9 "F.Adhes" user "F.Adhesive")
		(11 "B.Adhes" user "B.Adhesive")
		(13 "F.Paste" user "Package Geometry/Pastemask Top")
		(15 "B.Paste" user "Package Geometry/Pastemask Bottom")
		(5 "F.SilkS" user "Ref Des/Silkscreen Top")
		(7 "B.SilkS" user "Ref Des/Silkscreen Bottom")
		(1 "F.Mask" user "Board Geometry/Soldermask Top")
		(3 "B.Mask" user "Board Geometry/Soldermask Bottom")
		(17 "Dwgs.User" user "User.Drawings")
		(19 "Cmts.User" user "User.Comments")
		(21 "Eco1.User" user "User.Eco1")
		(23 "Eco2.User" user "User.Eco2")
		(25 "Edge.Cuts" user "Board Geometry/Outline")
		(27 "Margin" user)
		(31 "F.CrtYd" user "Package Geometry/Place Bound Top")
		(29 "B.CrtYd" user "Package Geometry/Place Bound Bottom")
		(35 "F.Fab" user "Ref Des/Assembly Top")
		(33 "B.Fab" user "Ref Des/Assembly Bottom")
	)
	(footprint ""
		(layer "F.Cu")
		(at 36.449 -366.776 -90)
		(property "Reference" "PC364"
			(at 0 0 270)
			(layer "F.SilkS")
			(hide yes)
			(effects
				(font
					(size 1.27 1.27)
				)
			)
		)
		(property "Value" ""
			(at 0 0 270)
			(layer "F.Fab")
			(effects
				(font
					(size 1.27 1.27)
				)
			)
		)
		(duplicate_pad_numbers_are_jumpers no)
		(fp_line
			(start -0.7874 0.4064)
			(end -0.7874 -0.4064)
			(stroke
				(width 0.1524)
				(type default)
			)
			(layer "F.SilkS")
		)
		(fp_line
			(start 0.7874 0.4064)
			(end -0.7874 0.4064)
			(stroke
				(width 0.1524)
				(type default)
			)
			(layer "F.SilkS")
		)
		(fp_line
			(start -0.7874 -0.4064)
			(end 0.7874 -0.4064)
			(stroke
				(width 0.1524)
				(type default)
			)
			(layer "F.SilkS")
		)
		(fp_line
			(start 0.7874 -0.4064)
			(end 0.7874 0.4064)
			(stroke
				(width 0.1524)
				(type default)
			)
			(layer "F.SilkS")
		)
		(fp_line
			(start -0.67945 0.3048)
			(end -0.67945 -0.305054)
			(stroke
				(width 0.1)
				(type default)
			)
			(layer "F.Fab")
		)
		(fp_line
			(start -0.12065 0.3048)
			(end -0.67945 0.3048)
			(stroke
				(width 0.1)
				(type default)
			)
			(layer "F.Fab")
		)
		(fp_line
			(start 0.120396 0.3048)
			(end 0.120396 0.2794)
			(stroke
				(width 0.1)
				(type default)
			)
			(layer "F.Fab")
		)
		(fp_line
			(start 0.67945 0.3048)
			(end 0.120396 0.3048)
			(stroke
				(width 0.1)
				(type default)
			)
			(layer "F.Fab")
		)
		(fp_line
			(start -0.12065 0.2794)
			(end -0.12065 0.3048)
			(stroke
				(width 0.1)
				(type default)
			)
			(layer "F.Fab")
		)
		(fp_line
			(start 0.120396 0.2794)
			(end -0.12065 0.2794)
			(stroke
				(width 0.1)
				(type default)
			)
			(layer "F.Fab")
		)
		(fp_line
			(start -0.12065 -0.2794)
			(end 0.12065 -0.2794)
			(stroke
				(width 0.1)
				(type default)
			)
			(layer "F.Fab")
		)
		(fp_line
			(start 0.12065 -0.2794)
			(end 0.12065 -0.3048)
			(stroke
				(width 0.1)
				(type default)
			)
			(layer "F.Fab")
		)
		(fp_line
			(start 0.12065 -0.3048)
			(end 0.67945 -0.3048)
			(stroke
				(width 0.1)
				(type default)
			)
			(layer "F.Fab")
		)
		(fp_line
			(start 0.67945 -0.3048)
			(end 0.67945 0.3048)
			(stroke
				(width 0.1)
				(type default)
			)
			(layer "F.Fab")
		)
		(fp_line
			(start -0.67945 -0.305054)
			(end -0.12065 -0.305054)
			(stroke
				(width 0.1)
				(type default)
			)
			(layer "F.Fab")
		)
		(fp_line
			(start -0.12065 -0.305054)
			(end -0.12065 -0.2794)
			(stroke
				(width 0.1)
				(type default)
			)
			(layer "F.Fab")
		)
		(pad "1" smd circle
			(at -0.40005 0 270)
			(size 0 0)
			(layers "F.Cu" "F.Mask" "F.Paste")
			(net "PVDDCR_CPU1_P1_VINSEN")
		)
		(pad "2" smd circle
			(at 0.40005 0 270)
			(size 0 0)
			(layers "F.Cu" "F.Mask" "F.Paste")
			(net "GND")
		)
	)
	(footprint ""
		(layer "F.Cu")
		(at 385.049268 -33.226502 180)
		(property "Reference" "R4601"
			(at 0 0 180)
			(layer "F.SilkS")
			(hide yes)
			(effects
				(font
					(size 1.27 1.27)
				)
			)
		)
		(property "Value" ""
			(at 0 0 180)
			(layer "F.Fab")
			(effects
				(font
					(size 1.27 1.27)
				)
			)
		)
		(duplicate_pad_numbers_are_jumpers no)
		(fp_line
			(start 0.7874 0.4064)
			(end -0.7874 0.4064)
			(stroke
				(width 0.1524)
				(type default)
			)
			(layer "F.SilkS")
		)
		(fp_line
			(start 0.7874 -0.4064)
			(end 0.7874 0.4064)
			(stroke
				(width 0.1524)
				(type default)
			)
			(layer "F.SilkS")
		)
		(fp_line
			(start -0.7874 0.4064)
			(end -0.7874 -0.4064)
			(stroke
				(width 0.1524)
				(type default)
			)
			(layer "F.SilkS")
		)
		(fp_line
			(start -0.7874 -0.4064)
			(end 0.7874 -0.4064)
			(stroke
				(width 0.1524)
				(type default)
			)
			(layer "F.SilkS")
		)
		(fp_line
			(start 0.67945 0.3048)
			(end 0.120396 0.3048)
			(stroke
				(width 0.1)
				(type default)
			)
			(layer "F.Fab")
		)
		(fp_line
			(start 0.67945 -0.3048)
			(end 0.67945 0.3048)
			(stroke
				(width 0.1)
				(type default)
			)
			(layer "F.Fab")
		)
		(fp_line
			(start 0.12065 -0.2794)
			(end 0.12065 -0.3048)
			(stroke
				(width 0.1)
				(type default)
			)
			(layer "F.Fab")
		)
		(fp_line
			(start 0.12065 -0.3048)
			(end 0.67945 -0.3048)
			(stroke
				(width 0.1)
				(type default)
			)
			(layer "F.Fab")
		)
		(fp_line
			(start 0.120396 0.3048)
			(end 0.120396 0.2794)
			(stroke
				(width 0.1)
				(type default)
			)
			(layer "F.Fab")
		)
		(fp_line
			(start 0.120396 0.2794)
			(end -0.12065 0.2794)
			(stroke
				(width 0.1)
				(type default)
			)
			(layer "F.Fab")
		)
		(fp_line
			(start -0.12065 0.3048)
			(end -0.67945 0.3048)
			(stroke
				(width 0.1)
				(type default)
			)
			(layer "F.Fab")
		)
		(fp_line
			(start -0.12065 0.2794)
			(end -0.12065 0.3048)
			(stroke
				(width 0.1)
				(type default)
			)
			(layer "F.Fab")
		)
		(fp_line
			(start -0.12065 -0.2794)
			(end 0.12065 -0.2794)
			(stroke
				(width 0.1)
				(type default)
			)
			(layer "F.Fab")
		)
		(fp_line
			(start -0.12065 -0.305054)
			(end -0.12065 -0.2794)
			(stroke
				(width 0.1)
				(type default)
			)
			(layer "F.Fab")
		)
		(fp_line
			(start -0.67945 0.3048)
			(end -0.67945 -0.305054)
			(stroke
				(width 0.1)
				(type default)
			)
			(layer "F.Fab")
		)
		(fp_line
			(start -0.67945 -0.305054)
			(end -0.12065 -0.305054)
			(stroke
				(width 0.1)
				(type default)
			)
			(layer "F.Fab")
		)
		(pad "1" smd circle
			(at -0.40005 0 180)
			(size 0 0)
			(layers "F.Cu" "F.Mask" "F.Paste")
			(net "CLK_50M_NCSI_OCP_SFF_ISO")
		)
		(pad "2" smd circle
			(at 0.40005 0 180)
			(size 0 0)
			(layers "F.Cu" "F.Mask" "F.Paste")
			(net "CLK_50M_NCSI_OCP_SFF_ISO_R")
		)
	)
	(footprint ""
		(layer "F.Cu")
		(at 205.214982 -115.657376 180)
		(property "Reference" "R6114"
			(at 0 0 180)
			(layer "F.SilkS")
			(hide yes)
			(effects
				(font
					(size 1.27 1.27)
				)
			)
		)
		(property "Value" ""
			(at 0 0 180)
			(layer "F.Fab")
			(effects
				(font
					(size 1.27 1.27)
				)
			)
		)
		(duplicate_pad_numbers_are_jumpers no)
		(fp_line
			(start 0.7874 0.4064)
			(end -0.7874 0.4064)
			(stroke
				(width 0.1524)
				(type default)
			)
			(layer "F.SilkS")
		)
		(fp_line
			(start 0.7874 -0.4064)
			(end 0.7874 0.4064)
			(stroke
				(width 0.1524)
				(type default)
			)
			(layer "F.SilkS")
		)
		(fp_line
			(start -0.7874 0.4064)
			(end -0.7874 -0.4064)
			(stroke
				(width 0.1524)
				(type default)
			)
			(layer "F.SilkS")
		)
		(fp_line
			(start -0.7874 -0.4064)
			(end 0.7874 -0.4064)
			(stroke
				(width 0.1524)
				(type default)
			)
			(layer "F.SilkS")
		)
		(fp_line
			(start 0.67945 0.3048)
			(end 0.120396 0.3048)
			(stroke
				(width 0.1)
				(type default)
			)
			(layer "F.Fab")
		)
		(fp_line
			(start 0.67945 -0.3048)
			(end 0.67945 0.3048)
			(stroke
				(width 0.1)
				(type default)
			)
			(layer "F.Fab")
		)
		(fp_line
			(start 0.12065 -0.2794)
			(end 0.12065 -0.3048)
			(stroke
				(width 0.1)
				(type default)
			)
			(layer "F.Fab")
		)
		(fp_line
			(start 0.12065 -0.3048)
			(end 0.67945 -0.3048)
			(stroke
				(width 0.1)
				(type default)
			)
			(layer "F.Fab")
		)
		(fp_line
			(start 0.120396 0.3048)
			(end 0.120396 0.2794)
			(stroke
				(width 0.1)
				(type default)
			)
			(layer "F.Fab")
		)
		(fp_line
			(start 0.120396 0.2794)
			(end -0.12065 0.2794)
			(stroke
				(width 0.1)
				(type default)
			)
			(layer "F.Fab")
		)
		(fp_line
			(start -0.12065 0.3048)
			(end -0.67945 0.3048)
			(stroke
				(width 0.1)
				(type default)
			)
			(layer "F.Fab")
		)
		(fp_line
			(start -0.12065 0.2794)
			(end -0.12065 0.3048)
			(stroke
				(width 0.1)
				(type default)
			)
			(layer "F.Fab")
		)
		(fp_line
			(start -0.12065 -0.2794)
			(end 0.12065 -0.2794)
			(stroke
				(width 0.1)
				(type default)
			)
			(layer "F.Fab")
		)
		(fp_line
			(start -0.12065 -0.305054)
			(end -0.12065 -0.2794)
			(stroke
				(width 0.1)
				(type default)
			)
			(layer "F.Fab")
		)
		(fp_line
			(start -0.67945 0.3048)
			(end -0.67945 -0.305054)
			(stroke
				(width 0.1)
				(type default)
			)
			(layer "F.Fab")
		)
		(fp_line
			(start -0.67945 -0.305054)
			(end -0.12065 -0.305054)
			(stroke
				(width 0.1)
				(type default)
			)
			(layer "F.Fab")
		)
		(pad "1" smd circle
			(at -0.40005 0 180)
			(size 0 0)
			(layers "F.Cu" "F.Mask" "F.Paste")
			(net "RST_PERST_CPU0_SWB_N")
		)
		(pad "2" smd circle
			(at 0.40005 0 180)
			(size 0 0)
			(layers "F.Cu" "F.Mask" "F.Paste")
			(net "GND")
		)
	)
	(footprint ""
		(layer "F.Cu")
		(at 451.327012 -30.397958 -90)
		(property "Reference" "PD101"
			(at 1.127506 -2.5654 90)
			(unlocked yes)
			(layer "F.SilkS")
			(effects
				(font
					(size 0.7874 0.5842)
					(thickness 0.1524)
				)
				(justify left)
			)
		)
		(property "Value" ""
			(at 0 0 270)
			(layer "F.Fab")
			(effects
				(font
					(size 1.27 1.27)
				)
			)
		)
		(duplicate_pad_numbers_are_jumpers no)
		(fp_line
			(start -2.250186 0.999998)
			(end 2.631186 0.999998)
			(stroke
				(width 0.1524)
				(type default)
			)
			(layer "F.SilkS")
		)
		(fp_line
			(start 2.631186 0.999998)
			(end 2.631186 -0.999998)
			(stroke
				(width 0.1524)
				(type default)
			)
			(layer "F.SilkS")
		)
		(fp_line
			(start -0.381 0.3302)
			(end -0.381 -0.4318)
			(stroke
				(width 0.1524)
				(type default)
			)
			(layer "F.SilkS")
		)
		(fp_line
			(start -0.381 -0.0508)
			(end -0.6604 -0.0508)
			(stroke
				(width 0.1524)
				(type default)
			)
			(layer "F.SilkS")
		)
		(fp_line
			(start 0.381 -0.0508)
			(end -0.381 0.3302)
			(stroke
				(width 0.1524)
				(type default)
			)
			(layer "F.SilkS")
		)
		(fp_line
			(start 0.381 -0.0508)
			(end 0.635 -0.0508)
			(stroke
				(width 0.1524)
				(type default)
			)
			(layer "F.SilkS")
		)
		(fp_line
			(start -0.381 -0.4318)
			(end 0.381 -0.0508)
			(stroke
				(width 0.1524)
				(type default)
			)
			(layer "F.SilkS")
		)
		(fp_line
			(start 0.381 -0.4318)
			(end 0.381 0.3302)
			(stroke
				(width 0.1524)
				(type default)
			)
			(layer "F.SilkS")
		)
		(fp_line
			(start -2.250186 -0.999998)
			(end -2.250186 0.999998)
			(stroke
				(width 0.1524)
				(type default)
			)
			(layer "F.SilkS")
		)
		(fp_line
			(start 2.631186 -0.999998)
			(end -2.250186 -0.999998)
			(stroke
				(width 0.1524)
				(type default)
			)
			(layer "F.SilkS")
		)
		(fp_rect
			(start 2.6162 1.016)
			(end 2.1844 -0.9652)
			(stroke
				(width 0)
				(type default)
			)
			(fill yes)
			(layer "F.SilkS")
		)
		(fp_line
			(start -1.450086 0.999998)
			(end 1.450086 0.999998)
			(stroke
				(width 0.1)
				(type default)
			)
			(layer "F.Fab")
		)
		(fp_line
			(start 1.450086 0.999998)
			(end 1.450086 -0.999998)
			(stroke
				(width 0.1)
				(type default)
			)
			(layer "F.Fab")
		)
		(fp_line
			(start -1.450086 -0.999998)
			(end -1.450086 0.999998)
			(stroke
				(width 0.1)
				(type default)
			)
			(layer "F.Fab")
		)
		(fp_line
			(start 1.450086 -0.999998)
			(end -1.450086 -0.999998)
			(stroke
				(width 0.1)
				(type default)
			)
			(layer "F.Fab")
		)
		(fp_text user "+"
			(at -3.4798 -0.22225 270)
			(unlocked yes)
			(layer "F.SilkS")
			(effects
				(font
					(size 1.905 1.4224)
					(thickness 0.1524)
				)
				(justify left)
			)
		)
		(fp_text user "-"
			(at 2.4384 -0.22225 270)
			(unlocked yes)
			(layer "F.SilkS")
			(effects
				(font
					(size 1.905 1.4224)
					(thickness 0.1524)
				)
				(justify left)
			)
		)
		(fp_text user "+"
			(at -3.4798 -0.22225 270)
			(unlocked yes)
			(layer "F.Fab")
			(effects
				(font
					(size 1.905 1.4224)
					(thickness 0.1524)
				)
				(justify left)
			)
		)
		(fp_text user "-"
			(at 2.4384 -0.22225 270)
			(unlocked yes)
			(layer "F.Fab")
			(effects
				(font
					(size 1.905 1.4224)
					(thickness 0.1524)
				)
				(justify left)
			)
		)
		(pad "A" smd rect
			(at -1.450086 0 270)
			(size 1.3208 1.4224)
			(layers "F.Cu" "F.Mask" "F.Paste")
			(net "GND")
		)
		(pad "C" smd rect
			(at 1.450086 0 270)
			(size 1.3208 1.4224)
			(layers "F.Cu" "F.Mask" "F.Paste")
			(net "P12V_AUX")
		)
	)
	(footprint ""
		(layer "F.Cu")
		(at 119.513096 -370.57203 -90)
		(property "Reference" "C1534"
			(at 0 0 270)
			(layer "F.SilkS")
			(hide yes)
			(effects
				(font
					(size 1.27 1.27)
				)
			)
		)
		(property "Value" ""
			(at 0 0 270)
			(layer "F.Fab")
			(effects
				(font
					(size 1.27 1.27)
				)
			)
		)
		(duplicate_pad_numbers_are_jumpers no)
		(fp_line
			(start -0.299974 0.150114)
			(end -0.299974 -0.150114)
			(stroke
				(width 0.1)
				(type default)
			)
			(layer "F.Fab")
		)
		(fp_line
			(start 0.299974 0.150114)
			(end -0.299974 0.150114)
			(stroke
				(width 0.1)
				(type default)
			)
			(layer "F.Fab")
		)
		(fp_line
			(start -0.299974 -0.150114)
			(end 0.299974 -0.150114)
			(stroke
				(width 0.1)
				(type default)
			)
			(layer "F.Fab")
		)
		(fp_line
			(start 0.299974 -0.150114)
			(end 0.299974 0.150114)
			(stroke
				(width 0.1)
				(type default)
			)
			(layer "F.Fab")
		)
		(pad "1" smd rect
			(at -0.2667 0 270)
			(size 0.3048 0.381)
			(layers "F.Cu" "F.Mask" "F.Paste")
			(net "P5E_CPU1_P3_TX_C_DN<6>")
		)
		(pad "2" smd rect
			(at 0.2667 0 270)
			(size 0.3048 0.381)
			(layers "F.Cu" "F.Mask" "F.Paste")
			(net "P5E_CPU1_P3_TX_DN<6>")
		)
	)
	(footprint ""
		(layer "F.Cu")
		(at 45.932344 -418.888164)
		(property "Reference" "R1465"
			(at 0 0 0)
			(layer "F.SilkS")
			(hide yes)
			(effects
				(font
					(size 1.27 1.27)
				)
			)
		)
		(property "Value" ""
			(at 0 0 0)
			(layer "F.Fab")
			(effects
				(font
					(size 1.27 1.27)
				)
			)
		)
		(duplicate_pad_numbers_are_jumpers no)
		(fp_line
			(start -0.32512 -0.175006)
			(end 0.32512 -0.175006)
			(stroke
				(width 0.1)
				(type default)
			)
			(layer "F.Fab")
		)
		(fp_line
			(start -0.32512 0.175006)
			(end -0.32512 -0.175006)
			(stroke
				(width 0.1)
				(type default)
			)
			(layer "F.Fab")
		)
		(fp_line
			(start 0.32512 -0.175006)
			(end 0.32512 0.175006)
			(stroke
				(width 0.1)
				(type default)
			)
			(layer "F.Fab")
		)
		(fp_line
			(start 0.32512 0.175006)
			(end -0.32512 0.175006)
			(stroke
				(width 0.1)
				(type default)
			)
			(layer "F.Fab")
		)
		(pad "1" smd rect
			(at -0.2667 0)
			(size 0.3048 0.381)
			(layers "F.Cu" "F.Mask" "F.Paste")
			(net "P1V8_CPU1_RT_1D")
		)
		(pad "2" smd rect
			(at 0.2667 0 180)
			(size 0.3048 0.381)
			(layers "F.Cu" "F.Mask" "F.Paste")
			(net "JTAG_TMS_RT_CPU1_P0")
		)
	)
	(footprint ""
		(layer "F.Cu")
		(at 169.744644 -128.24333)
		(property "Reference" "R6851"
			(at 0 0 0)
			(layer "F.SilkS")
			(hide yes)
			(effects
				(font
					(size 1.27 1.27)
				)
			)
		)
		(property "Value" ""
			(at 0 0 0)
			(layer "F.Fab")
			(effects
				(font
					(size 1.27 1.27)
				)
			)
		)
		(duplicate_pad_numbers_are_jumpers no)
		(fp_line
			(start -0.7874 -0.4064)
			(end 0.7874 -0.4064)
			(stroke
				(width 0.1524)
				(type default)
			)
			(layer "F.SilkS")
		)
		(fp_line
			(start -0.7874 0.4064)
			(end -0.7874 -0.4064)
			(stroke
				(width 0.1524)
				(type default)
			)
			(layer "F.SilkS")
		)
		(fp_line
			(start 0.7874 -0.4064)
			(end 0.7874 0.4064)
			(stroke
				(width 0.1524)
				(type default)
			)
			(layer "F.SilkS")
		)
		(fp_line
			(start 0.7874 0.4064)
			(end -0.7874 0.4064)
			(stroke
				(width 0.1524)
				(type default)
			)
			(layer "F.SilkS")
		)
		(fp_line
			(start -0.67945 -0.305054)
			(end -0.12065 -0.305054)
			(stroke
				(width 0.1)
				(type default)
			)
			(layer "F.Fab")
		)
		(fp_line
			(start -0.67945 0.3048)
			(end -0.67945 -0.305054)
			(stroke
				(width 0.1)
				(type default)
			)
			(layer "F.Fab")
		)
		(fp_line
			(start -0.12065 -0.305054)
			(end -0.12065 -0.2794)
			(stroke
				(width 0.1)
				(type default)
			)
			(layer "F.Fab")
		)
		(fp_line
			(start -0.12065 -0.2794)
			(end 0.12065 -0.2794)
			(stroke
				(width 0.1)
				(type default)
			)
			(layer "F.Fab")
		)
		(fp_line
			(start -0.12065 0.2794)
			(end -0.12065 0.3048)
			(stroke
				(width 0.1)
				(type default)
			)
			(layer "F.Fab")
		)
		(fp_line
			(start -0.12065 0.3048)
			(end -0.67945 0.3048)
			(stroke
				(width 0.1)
				(type default)
			)
			(layer "F.Fab")
		)
		(fp_line
			(start 0.120396 0.2794)
			(end -0.12065 0.2794)
			(stroke
				(width 0.1)
				(type default)
			)
			(layer "F.Fab")
		)
		(fp_line
			(start 0.120396 0.3048)
			(end 0.120396 0.2794)
			(stroke
				(width 0.1)
				(type default)
			)
			(layer "F.Fab")
		)
		(fp_line
			(start 0.12065 -0.3048)
			(end 0.67945 -0.3048)
			(stroke
				(width 0.1)
				(type default)
			)
			(layer "F.Fab")
		)
		(fp_line
			(start 0.12065 -0.2794)
			(end 0.12065 -0.3048)
			(stroke
				(width 0.1)
				(type default)
			)
			(layer "F.Fab")
		)
		(fp_line
			(start 0.67945 -0.3048)
			(end 0.67945 0.3048)
			(stroke
				(width 0.1)
				(type default)
			)
			(layer "F.Fab")
		)
		(fp_line
			(start 0.67945 0.3048)
			(end 0.120396 0.3048)
			(stroke
				(width 0.1)
				(type default)
			)
			(layer "F.Fab")
		)
		(pad "1" smd circle
			(at -0.40005 0)
			(size 0 0)
			(layers "F.Cu" "F.Mask" "F.Paste")
			(net "P1V8_RETIMER_CPU1_EN")
		)
		(pad "2" smd circle
			(at 0.40005 0)
			(size 0 0)
			(layers "F.Cu" "F.Mask" "F.Paste")
			(net "P1V8_RETIMER_CPU1_R_EN")
		)
	)
)
